# T6G (Grand Teton) — schematic netlist excerpt (pin names and nets, part order shuffled) for the footprints in the layout excerpt that follows; sources: Cadence DE-HDL packaged netlist, KiCad conversion of 04192023_DAF0TMB3IC0_F0TG_MB_C_brd_V02_OCP.brd

R91  Q_RES  1K 1% EMPTY  pkg 0402LF  page 88 : A = P3V3 ; B = PWRGD_CHC_CPU0_DIMM
PC1855  Q_CAP  22UF 10V 20% X6S  pkg C0805  page 189 : A = P5V_AUX ; B = GND
R8565  Q_RES  0 5% CHIP  pkg 0402LF  page 28 : A = CLK_100M_CPU0_CLK03_R_DP ; B = CLK_100M_CPU0_CLK03_DP

(kicad_pcb
	(version 20260206)
	(generator "pcbnew")
	(generator_version "10.0")
	(general
		(thickness 1.6)
		(legacy_teardrops no)
	)
	(paper "A4")
	(title_block
		(title "04192023_DAF0TMB3IC0_F0TG_MB_C_brd_V02_OCP.brd")
		(comment 1 "Grand Teton / footprints 7767-7769 of 8354")
	)
	(layers
		(0 "F.Cu" signal "TOP")
		(4 "In1.Cu" signal "GND")
		(6 "In2.Cu" signal "IN1")
		(8 "In3.Cu" signal "GND1")
		(10 "In4.Cu" signal "IN2")
		(12 "In5.Cu" signal "GND2")
		(14 "In6.Cu" signal "IN3")
		(16 "In7.Cu" signal "GND3")
		(18 "In8.Cu" signal "VCC")
		(20 "In9.Cu" signal "VCC1")
		(22 "In10.Cu" signal "GND4")
		(24 "In11.Cu" signal "IN4")
		(26 "In12.Cu" signal "GND5")
		(28 "In13.Cu" signal "IN5")
		(30 "In14.Cu" signal "GND6")
		(32 "In15.Cu" signal "IN6")
		(34 "In16.Cu" signal "GND7")
		(2 "B.Cu" signal "BOTTOM")
		(9 "F.Adhes" user "F.Adhesive")
		(11 "B.Adhes" user "B.Adhesive")
		(13 "F.Paste" user "Package Geometry/Pastemask Top")
		(15 "B.Paste" user "Package Geometry/Pastemask Bottom")
		(5 "F.SilkS" user "Ref Des/Silkscreen Top")
		(7 "B.SilkS" user "Ref Des/Silkscreen Bottom")
		(1 "F.Mask" user "Board Geometry/Soldermask Top")
		(3 "B.Mask" user "Board Geometry/Soldermask Bottom")
		(17 "Dwgs.User" user "User.Drawings")
		(19 "Cmts.User" user "User.Comments")
		(21 "Eco1.User" user "User.Eco1")
		(23 "Eco2.User" user "User.Eco2")
		(25 "Edge.Cuts" user "Board Geometry/Outline")
		(27 "Margin" user)
		(31 "F.CrtYd" user "Package Geometry/Place Bound Top")
		(29 "B.CrtYd" user "Package Geometry/Place Bound Bottom")
		(35 "F.Fab" user "Ref Des/Assembly Top")
		(33 "B.Fab" user "Ref Des/Assembly Bottom")
	)
	(footprint ""
		(layer "B.Cu")
		(at 288.935668 -193.99631)
		(property "Reference" "R91"
			(at 0 0 0)
			(layer "B.SilkS")
			(hide yes)
			(effects
				(font
					(size 1.27 1.27)
				)
				(justify mirror)
			)
		)
		(property "Value" ""
			(at 0 0 0)
			(layer "B.Fab")
			(effects
				(font
					(size 1.27 1.27)
				)
				(justify mirror)
			)
		)
		(duplicate_pad_numbers_are_jumpers no)
		(fp_line
			(start -0.7874 -0.4064)
			(end -0.7874 0.4064)
			(stroke
				(width 0.1524)
				(type default)
			)
			(layer "B.SilkS")
		)
		(fp_line
			(start -0.7874 0.4064)
			(end 0.7874 0.4064)
			(stroke
				(width 0.1524)
				(type default)
			)
			(layer "B.SilkS")
		)
		(fp_line
			(start 0.7874 -0.4064)
			(end -0.7874 -0.4064)
			(stroke
				(width 0.1524)
				(type default)
			)
			(layer "B.SilkS")
		)
		(fp_line
			(start 0.7874 0.4064)
			(end 0.7874 -0.4064)
			(stroke
				(width 0.1524)
				(type default)
			)
			(layer "B.SilkS")
		)
		(fp_line
			(start -0.67945 -0.3048)
			(end -0.67945 0.3048)
			(stroke
				(width 0.1)
				(type default)
			)
			(layer "B.Fab")
		)
		(fp_line
			(start -0.67945 0.3048)
			(end -0.120396 0.3048)
			(stroke
				(width 0.1)
				(type default)
			)
			(layer "B.Fab")
		)
		(fp_line
			(start -0.12065 -0.3048)
			(end -0.67945 -0.3048)
			(stroke
				(width 0.1)
				(type default)
			)
			(layer "B.Fab")
		)
		(fp_line
			(start -0.12065 -0.2794)
			(end -0.12065 -0.3048)
			(stroke
				(width 0.1)
				(type default)
			)
			(layer "B.Fab")
		)
		(fp_line
			(start -0.120396 0.2794)
			(end 0.12065 0.2794)
			(stroke
				(width 0.1)
				(type default)
			)
			(layer "B.Fab")
		)
		(fp_line
			(start -0.120396 0.3048)
			(end -0.120396 0.2794)
			(stroke
				(width 0.1)
				(type default)
			)
			(layer "B.Fab")
		)
		(fp_line
			(start 0.12065 -0.305054)
			(end 0.12065 -0.2794)
			(stroke
				(width 0.1)
				(type default)
			)
			(layer "B.Fab")
		)
		(fp_line
			(start 0.12065 -0.2794)
			(end -0.12065 -0.2794)
			(stroke
				(width 0.1)
				(type default)
			)
			(layer "B.Fab")
		)
		(fp_line
			(start 0.12065 0.2794)
			(end 0.12065 0.3048)
			(stroke
				(width 0.1)
				(type default)
			)
			(layer "B.Fab")
		)
		(fp_line
			(start 0.12065 0.3048)
			(end 0.67945 0.3048)
			(stroke
				(width 0.1)
				(type default)
			)
			(layer "B.Fab")
		)
		(fp_line
			(start 0.67945 -0.305054)
			(end 0.12065 -0.305054)
			(stroke
				(width 0.1)
				(type default)
			)
			(layer "B.Fab")
		)
		(fp_line
			(start 0.67945 0.3048)
			(end 0.67945 -0.305054)
			(stroke
				(width 0.1)
				(type default)
			)
			(layer "B.Fab")
		)
		(pad "1" smd circle
			(at 0.40005 0 180)
			(size 0 0)
			(layers "B.Cu" "B.Mask" "B.Paste")
			(net "P3V3")
		)
		(pad "2" smd circle
			(at -0.40005 0 180)
			(size 0 0)
			(layers "B.Cu" "B.Mask" "B.Paste")
			(net "PWRGD_CHC_CPU0_DIMM")
		)
	)
	(footprint ""
		(layer "B.Cu")
		(at 376.722386 -214.523828 90)
		(property "Reference" "R8565"
			(at 0 0 90)
			(layer "B.SilkS")
			(hide yes)
			(effects
				(font
					(size 1.27 1.27)
				)
				(justify mirror)
			)
		)
		(property "Value" ""
			(at 0 0 90)
			(layer "B.Fab")
			(effects
				(font
					(size 1.27 1.27)
				)
				(justify mirror)
			)
		)
		(duplicate_pad_numbers_are_jumpers no)
		(fp_line
			(start 0.385572 -0.4064)
			(end -0.351028 -0.4064)
			(stroke
				(width 0.1524)
				(type default)
			)
			(layer "B.SilkS")
		)
		(fp_line
			(start -0.7874 0.086614)
			(end -0.7874 0.4064)
			(stroke
				(width 0.1524)
				(type default)
			)
			(layer "B.SilkS")
		)
		(fp_line
			(start 0.7874 0.4064)
			(end 0.7874 -0.014986)
			(stroke
				(width 0.1524)
				(type default)
			)
			(layer "B.SilkS")
		)
		(fp_line
			(start -0.7874 0.4064)
			(end 0.7874 0.4064)
			(stroke
				(width 0.1524)
				(type default)
			)
			(layer "B.SilkS")
		)
		(fp_line
			(start 0.67945 -0.305054)
			(end 0.12065 -0.305054)
			(stroke
				(width 0.1)
				(type default)
			)
			(layer "B.Fab")
		)
		(fp_line
			(start 0.12065 -0.305054)
			(end 0.12065 -0.2794)
			(stroke
				(width 0.1)
				(type default)
			)
			(layer "B.Fab")
		)
		(fp_line
			(start -0.12065 -0.3048)
			(end -0.67945 -0.3048)
			(stroke
				(width 0.1)
				(type default)
			)
			(layer "B.Fab")
		)
		(fp_line
			(start -0.67945 -0.3048)
			(end -0.67945 0.3048)
			(stroke
				(width 0.1)
				(type default)
			)
			(layer "B.Fab")
		)
		(fp_line
			(start 0.12065 -0.2794)
			(end -0.12065 -0.2794)
			(stroke
				(width 0.1)
				(type default)
			)
			(layer "B.Fab")
		)
		(fp_line
			(start -0.12065 -0.2794)
			(end -0.12065 -0.3048)
			(stroke
				(width 0.1)
				(type default)
			)
			(layer "B.Fab")
		)
		(fp_line
			(start 0.12065 0.2794)
			(end 0.12065 0.3048)
			(stroke
				(width 0.1)
				(type default)
			)
			(layer "B.Fab")
		)
		(fp_line
			(start -0.120396 0.2794)
			(end 0.12065 0.2794)
			(stroke
				(width 0.1)
				(type default)
			)
			(layer "B.Fab")
		)
		(fp_line
			(start 0.67945 0.3048)
			(end 0.67945 -0.305054)
			(stroke
				(width 0.1)
				(type default)
			)
			(layer "B.Fab")
		)
		(fp_line
			(start 0.12065 0.3048)
			(end 0.67945 0.3048)
			(stroke
				(width 0.1)
				(type default)
			)
			(layer "B.Fab")
		)
		(fp_line
			(start -0.120396 0.3048)
			(end -0.120396 0.2794)
			(stroke
				(width 0.1)
				(type default)
			)
			(layer "B.Fab")
		)
		(fp_line
			(start -0.67945 0.3048)
			(end -0.120396 0.3048)
			(stroke
				(width 0.1)
				(type default)
			)
			(layer "B.Fab")
		)
		(pad "1" smd circle
			(at 0.40005 0 270)
			(size 0 0)
			(layers "B.Cu" "B.Mask" "B.Paste")
			(net "CLK_100M_CPU0_CLK03_R_DP")
		)
		(pad "2" smd circle
			(at -0.40005 0 270)
			(size 0 0)
			(layers "B.Cu" "B.Mask" "B.Paste")
			(net "CLK_100M_CPU0_CLK03_DP")
		)
	)
	(footprint ""
		(layer "B.Cu")
		(at 414.085786 -151.33701 90)
		(property "Reference" "PC1855"
			(at 0 0 90)
			(layer "B.SilkS")
			(hide yes)
			(effects
				(font
					(size 1.27 1.27)
				)
				(justify mirror)
			)
		)
		(property "Value" ""
			(at 0 0 90)
			(layer "B.Fab")
			(effects
				(font
					(size 1.27 1.27)
				)
				(justify mirror)
			)
		)
		(duplicate_pad_numbers_are_jumpers no)
		(fp_line
			(start 1.524 -0.762)
			(end -1.524 -0.762)
			(stroke
				(width 0.1524)
				(type default)
			)
			(layer "B.SilkS")
		)
		(fp_line
			(start -1.524 -0.762)
			(end -1.524 0.762)
			(stroke
				(width 0.1524)
				(type default)
			)
			(layer "B.SilkS")
		)
		(fp_line
			(start 1.524 0.762)
			(end 1.524 -0.762)
			(stroke
				(width 0.1524)
				(type default)
			)
			(layer "B.SilkS")
		)
		(fp_line
			(start -1.524 0.762)
			(end 1.524 0.762)
			(stroke
				(width 0.1524)
				(type default)
			)
			(layer "B.SilkS")
		)
		(fp_line
			(start 1.1049 -0.724916)
			(end 1.1049 0.724916)
			(stroke
				(width 0.1)
				(type default)
			)
			(layer "B.Fab")
		)
		(fp_line
			(start -1.1049 -0.724916)
			(end 1.1049 -0.724916)
			(stroke
				(width 0.1)
				(type default)
			)
			(layer "B.Fab")
		)
		(fp_line
			(start 1.1049 0.724916)
			(end -1.1049 0.724916)
			(stroke
				(width 0.1)
				(type default)
			)
			(layer "B.Fab")
		)
		(fp_line
			(start -1.1049 0.724916)
			(end -1.1049 -0.724916)
			(stroke
				(width 0.1)
				(type default)
			)
			(layer "B.Fab")
		)
		(pad "1" smd rect
			(at 0.889 0 90)
			(size 1.016 1.27)
			(layers "B.Cu" "B.Mask" "B.Paste")
			(net "P5V_AUX")
		)
		(pad "2" smd rect
			(at -0.889 0 90)
			(size 1.016 1.27)
			(layers "B.Cu" "B.Mask" "B.Paste")
			(net "GND")
		)
	)
)
